FILE_TYPE = CONNECTIVITY;
{Allegro Design Entry HDL 16.6-p007 (v16-6-112F) 10/10/2012}
"PAGE_NUMBER" = 137;
0"NC";
1"GND\g";
2"P3V3_STBY\g";
3"GND\g";
4"P3V3_STBY\g";
5"GND\g";
6"GND\g";
7"P3V3_STBY\g";
8"GND\g";
9"P3V3_RTC_STBY\g";
10"P3V3_RTC_STBY\g";
11"RST_RTCRST_N";
12"PU_UV_HIGH_SET";
13"PD_UV_HIGH_SET";
14"FM_UART_PRES_N";
15"PD_RST_RTCRST_N";
16"UV_HIGH_SET";
17"TP_IE_DEBUG_MODE";
18"PU_SPI_BMC_BT_CS0_N";
19"SPI_BMC_BT_CS0_N";
20"TPM_SPI_BMC_WP_N"CDS_PHYS_NET_NAME"TPM_SPI_BMC_WP_N";
21"SPI_BMC_BT_WP0_N";
22"RST_SRTCRST_N";
23"TP_RST_RTCRST_N";
24"PD_SPI_BMC_BT_CS0_N";
25"PD_IE_DEBUG_MODE";
%"RES"
"1","(325,3450)","1","mstr_discrete","I11";
;
MATERIAL"EMPTY"
TOLERANCE"1%"
VALUE"1.0M"
LOCATION"R7C11"
PACK_TYPE"0402"
PART_NUMBER"G21796-021"
WATTAGE"1/16W"
ROOM"SB"
CDS_LOCATION"R7C11"
$SEC"1"
CDS_SEC"1"
BOM_COST"SB"
CDS_LIB"mstr_discrete";
"B"
$PN"2"11;
"A"
$PN"1"5;
%"CONN12_C73564003"
"1","(-2175,3675)","0","mstr_conn","I128";
;
CDS_SEC"1"
CDS_LOCATION"J9G1"
MATERIAL"CONN"
LOCATION"J9G1"
PART_NUMBER"C73564-003"
BOM_COST"SB"
CDS_LIB"mstr_conn"
SEC"1"
SEC_TYPE"PIP"
ROOM"SB"
PACK_TYPE"PIP";
"IO9"
$PN"9"14;
"IO11"
$PN"11"25;
"IO7"
$PN"7"17;
"IO3"
$PN"3"16;
"IO1"
$PN"1"12;
"IO5"
$PN"5"13;
"IO8"
$PN"8"18;
"IO10"
$PN"10"19;
"IO12"
$PN"12"24;
"IO6"
$PN"6"15;
"IO4"
$PN"4"11;
"IO2"
$PN"2"23;
%"RES"
"2","(-200,4025)","0","mstr_discrete","I13";
;
CDS_SEC"1"
MATERIAL"CHIP"
TOLERANCE"1%"
VALUE"20.0K"
WATTAGE"1/16W"
LOCATION"R7C10"
PART_NUMBER"G21796-040"
PACK_TYPE"0402"
CDS_LIB"mstr_discrete"
CDS_LOCATION"R7C10"
BOM_COST"SB"
SEC"1"
NO_XNET_CONNECTION"1"
SEC_TYPE"0402"
ROOM"SB";
"A"
$PN"1"9;
"B"
$PN"2"11;
%"RES"
"1","(-1700,2350)","0","mstr_discrete","I133";
;
VALUE"0.0"
MATERIAL"CHIP"
PART_NUMBER"G21497-005"
TOLERANCE"5%"
WATTAGE"1/16W"
SEC_TYPE"0402"
LOCATION"R25W154"
CDS_SEC"1"
PACK_TYPE"0402"
BOM_COST"SM_CONTROLLER"
ROOM"BMC"
SEC"1"
CDS_LIB"mstr_discrete"
CDS_LOCATION"R25W154";
"B"
$PN"2"20;
"A"
$PN"1"21;
%"CAP_A"
"1","(-125,3450)","0","dev_discrete","I14";
;
VOLTAGE"6.3V"
VALUE"1.0UF"
TOLERANCE"10%"
MATERIAL"X6S"
PACK_TYPE"0402V"
PART_NUMBER"D97712-004"
LOCATION"C7C19"
CDS_LOCATION"C7C19"
CDS_LIB"dev_discrete"
BOM_COST"SB"
CDS_SEC"1"
SEC_TYPE"0402V"
SEC"1"
ROOM"SB";
"B"
$PN"2"5;
"A"
$PN"1"11;
%"RES"
"1","(-1250,3300)","1","mstr_discrete","I140";
;
CDS_SEC"1"
TOLERANCE"1%"
WATTAGE"1/16W"
MATERIAL"CHIP"
VALUE"4.75K"
LOCATION"R25W94"
PACK_TYPE"0402"
PART_NUMBER"G21796-072"
CDS_LOCATION"R25W94"
CDS_LIB"mstr_discrete"
BOM_COST"SM_CONTROLLER"
ROOM"BMC"
SEC_TYPE"0402"
SEC"1";
"B"
$PN"2"24;
"A"
$PN"1"1;
%"GND"
"1","(-1250,3100)","0","mstr_symbols","I141";
;
SIZE"1B"
VOLTAGE"0.0V"
CDS_LIB"mstr_symbols"
BODY_TYPE"PLUMBING"
HDL_POWER"GND";
"A\NAC"1;
%"RES"
"2","(-1250,4100)","2","mstr_discrete","I142";
;
LOCATION"RN8F1"
MATERIAL"CHIP"
TOLERANCE"1%"
PACK_TYPE"0402"
PART_NUMBER"G21796-072"
WATTAGE"1/16W"
VALUE"4.75K"
CDS_LOCATION"RN8F1"
CDS_SEC"1"
CDS_LIB"mstr_discrete"
BOM_COST"SM_MEM"
SEC_TYPE"0402"
ROOM"BMC_BOOT_SPI"
SEC"1";
"A"
$PN"1"2;
"B"
$PN"2"18;
%"P3V3_STBY"
"1","(-1250,4400)","0","mstr_symbols","I143";
;
SIZE"1B"
CDS_LIB"mstr_symbols"
VOLTAGE"3.3V"
BODY_TYPE"PLUMBING"
HDL_POWER"P3V3_STBY";
"G\NAC"2;
%"RES"
"2","(-4500,3450)","0","mstr_discrete","I144";
;
TOLERANCE"1%"
MATERIAL"CHIP"
LOCATION"R6W2"
VALUE"10.0K"
PACK_TYPE"0402"
PART_NUMBER"G21796-016"
WATTAGE"1/16W"
ROOM"HOT_SWAP"
CDS_LIB"mstr_discrete"
CDS_LOCATION"R6W2"
$SEC"1"
CDS_SEC"1";
"A"
$PN"1"13;
"B"
$PN"2"3;
%"GND"
"1","(-4500,3250)","0","mstr_symbols","I145";
;
CDS_LIB"mstr_symbols"
VOLTAGE"0.0V"
SIZE"1B"
BODY_TYPE"PLUMBING"
HDL_POWER"GND";
"A\NAC"3;
%"P3V3_STBY"
"1","(-4500,4200)","0","mstr_symbols","I146";
;
CDS_LIB"mstr_symbols"
SIZE"1B"
VOLTAGE"+3.3V"
BODY_TYPE"PLUMBING"
HDL_POWER"P3V3_STBY";
"G\NAC"4;
%"RES"
"2","(-4500,3975)","0","mstr_discrete","I149";
;
MATERIAL"CHIP"
PART_NUMBER"G21796-072"
TOLERANCE"1%"
VALUE"4.75K"
PACK_TYPE"0402"
LOCATION"R6W1"
WATTAGE"1/16W"
SEC"1"
SEC_TYPE"0402"
CDS_LIB"mstr_discrete"
BOM_COST"SM_THERM"
ROOM"CPU_FANS"
CDS_SEC"1"
CDS_LOCATION"R6W1";
"A"
$PN"1"4;
"B"
$PN"2"12;
%"RES"
"2","(-275,3450)","2","mstr_discrete","I15";
;
CDS_SEC"1"
CDS_LOCATION"R1U63"
PART_NUMBER"G21796-026"
WATTAGE"1/16W"
TOLERANCE"1%"
VALUE"1.00K"
LOCATION"R1U63"
MATERIAL"CHIP"
PACK_TYPE"0402"
CDS_LIB"mstr_discrete"
SEC"1"
SEC_TYPE"0402"
BOM_COST"SB"
ROOM"SB";
"A"
$PN"1"15;
"B"
$PN"2"5;
%"GND"
"1","(-275,3125)","0","mstr_symbols","I16";
;
CDS_LIB"mstr_symbols"
BOM_COST"SB"
SIZE"1B"
ROOM"WBG_HEADERS_BIOS"
VOLTAGE"0"
BODY_TYPE"PLUMBING"
HDL_POWER"GND";
"A\NAC"5;
%"RES"
"2","(-300,1900)","0","mstr_discrete","I19";
;
MATERIAL"CHIP"
TOLERANCE"1%"
LOCATION"R3N4"
WATTAGE"1/16W"
PACK_TYPE"0402"
PART_NUMBER"G21796-040"
VALUE"20.0K"
CDS_LIB"mstr_discrete"
CDS_LOCATION"R3N4"
BOM_COST"SB"
CDS_SEC"1"
$SEC"1"
NO_XNET_CONNECTION"1"
ROOM"SB";
"A"
$PN"1"10;
"B"
$PN"2"22;
%"CAP_A"
"1","(-300,1450)","0","dev_discrete","I20";
;
MATERIAL"X6S"
VOLTAGE"6.3V"
PACK_TYPE"0402V"
TOLERANCE"10%"
VALUE"1.0UF"
PART_NUMBER"D97712-004"
LOCATION"C3N32"
CDS_LIB"dev_discrete"
SEC"1"
SEC_TYPE"0402V"
CDS_SEC"1"
BOM_COST"SB"
CDS_LOCATION"C3N32"
ROOM"SB";
"B"
$PN"2"6;
"A"
$PN"1"22;
%"GND"
"1","(-300,1250)","0","mstr_symbols","I21";
;
CDS_LIB"mstr_symbols"
BOM_COST"SB"
SIZE"1B"
ROOM"WBG_HEADERS_BIOS"
VOLTAGE"0"
BODY_TYPE"PLUMBING"
HDL_POWER"GND";
"A\NAC"6;
%"RES"
"2","(-2650,4225)","0","mstr_discrete","I67";
;
CDS_SEC"1"
LOCATION"R7C13"
PACK_TYPE"0402"
TOLERANCE"1%"
VALUE"10.0K"
WATTAGE"1/16W"
PART_NUMBER"G21796-016"
MATERIAL"CHIP"
ROOM"SB"
SEC"1"
BOM_COST"SB"
SEC_TYPE"0402"
CDS_LOCATION"R7C13"
CDS_LIB"mstr_discrete";
"A"
$PN"1"7;
"B"
$PN"2"14;
%"P3V3_STBY"
"1","(-2650,4450)","0","mstr_symbols","I68";
;
SIZE"1B"
CDS_LIB"mstr_symbols"
VOLTAGE"3.3V"
BODY_TYPE"PLUMBING"
HDL_POWER"P3V3_STBY";
"G\NAC"7;
%"RES"
"2","(-3150,3275)","0","mstr_discrete","I69";
;
CDS_SEC"1"
CDS_LOCATION"R1U64"
WATTAGE"1/16W"
PACK_TYPE"0402"
MATERIAL"CHIP"
PART_NUMBER"G21796-026"
VALUE"1.00K"
LOCATION"R1U64"
TOLERANCE"1%"
ROOM"SB"
BOM_COST"SB"
SEC_TYPE"0402"
SEC"1"
CDS_LIB"mstr_discrete";
"A"
$PN"1"25;
"B"
$PN"2"8;
%"GND"
"1","(-3150,3000)","0","mstr_symbols","I70";
;
VOLTAGE"0"
ROOM"WBG_HEADERS_BIOS"
BOM_COST"SB"
SIZE"1B"
CDS_LIB"mstr_symbols"
BODY_TYPE"PLUMBING"
HDL_POWER"GND";
"A\NAC"8;
%"P3V3_RTC_STBY"
"1","(-200,4225)","0","mstr_symbols","I78";
;
CDS_LIB"mstr_symbols"
BOM_COST"SB"
ROOM"SB_DECOUPLING"
VOLTAGE"3.3V"
BODY_TYPE"PLUMBING"
HDL_POWER"P3V3_RTC_STBY";
"G\NAC"9;
%"P3V3_RTC_STBY"
"1","(-300,2150)","0","mstr_symbols","I79";
;
BOM_COST"SB"
CDS_LIB"mstr_symbols"
ROOM"SB_DECOUPLING"
VOLTAGE"3.3V"
BODY_TYPE"PLUMBING"
HDL_POWER"P3V3_RTC_STBY";
"G\NAC"10;
END.
